# S9S_MB_2U (Grand Teton) — schematic netlist excerpt (pin names and nets, part order shuffled) for the footprints in the layout excerpt that follows; sources: Cadence DE-HDL packaged netlist, KiCad conversion of 03242023_DA0F0TMBIJ0_F0T_Motherboard_J_brd_V01_OCP.brd

R1467  Q_RES  4.7K 1% EMPTY  pkg 0402LF  page 213 : A = P3V3_AUX ; B = SMB_1_PLD_3V3AUX_SCL_R1
PC431  Q_CAP  100NF 50V 10% X7R  pkg C0402  page 294 : A = SW_PVCCFA_EHV_CPU1_BOOT1_R ; B = SW_PVCCFA_EHV_CPU1_BOOTR1
PJ49  Q_SHORT  EMPTY  pkg SM  page 284 : \1\ = VSENSE_PVCCFA_EHV_FIVRA_CPU1_DP ; \2\ = SH_PVCCFA_EHV_FIVRA_CPU1

(kicad_pcb
	(version 20260206)
	(generator "pcbnew")
	(generator_version "10.0")
	(general
		(thickness 1.6)
		(legacy_teardrops no)
	)
	(paper "A4")
	(title_block
		(title "03242023_DA0F0TMBIJ0_F0T_Motherboard_J_brd_V01_OCP.brd")
		(comment 1 "Grand Teton / footprints 3804-3806 of 6105")
	)
	(layers
		(0 "F.Cu" signal "TOP")
		(4 "In1.Cu" signal "GND")
		(6 "In2.Cu" signal "IN1")
		(8 "In3.Cu" signal "GND1")
		(10 "In4.Cu" signal "IN2")
		(12 "In5.Cu" signal "GND2")
		(14 "In6.Cu" signal "IN3")
		(16 "In7.Cu" signal "GND3")
		(18 "In8.Cu" signal "VCC")
		(20 "In9.Cu" signal "VCC1")
		(22 "In10.Cu" signal "GND4")
		(24 "In11.Cu" signal "IN4")
		(26 "In12.Cu" signal "GND5")
		(28 "In13.Cu" signal "IN5")
		(30 "In14.Cu" signal "GND6")
		(32 "In15.Cu" signal "IN6")
		(34 "In16.Cu" signal "GND7")
		(2 "B.Cu" signal "BOTTOM")
		(9 "F.Adhes" user "F.Adhesive")
		(11 "B.Adhes" user "B.Adhesive")
		(13 "F.Paste" user "Package Geometry/Pastemask Top")
		(15 "B.Paste" user "Package Geometry/Pastemask Bottom")
		(5 "F.SilkS" user "Ref Des/Silkscreen Top")
		(7 "B.SilkS" user "Ref Des/Silkscreen Bottom")
		(1 "F.Mask" user "Board Geometry/Soldermask Top")
		(3 "B.Mask" user "Board Geometry/Soldermask Bottom")
		(17 "Dwgs.User" user "User.Drawings")
		(19 "Cmts.User" user "User.Comments")
		(21 "Eco1.User" user "User.Eco1")
		(23 "Eco2.User" user "User.Eco2")
		(25 "Edge.Cuts" user "Board Geometry/Outline")
		(27 "Margin" user)
		(31 "F.CrtYd" user "Package Geometry/Place Bound Top")
		(29 "B.CrtYd" user "Package Geometry/Place Bound Bottom")
		(35 "F.Fab" user "Ref Des/Assembly Top")
		(33 "B.Fab" user "Ref Des/Assembly Bottom")
	)
	(footprint ""
		(layer "F.Cu")
		(at 160.83788 -116.296948)
		(property "Reference" "R1467"
			(at 0 0 0)
			(layer "F.SilkS")
			(hide yes)
			(effects
				(font
					(size 1.27 1.27)
				)
			)
		)
		(property "Value" ""
			(at 0 0 0)
			(layer "F.Fab")
			(effects
				(font
					(size 1.27 1.27)
				)
			)
		)
		(duplicate_pad_numbers_are_jumpers no)
		(fp_line
			(start -0.7874 -0.4064)
			(end 0.7874 -0.4064)
			(stroke
				(width 0.1524)
				(type default)
			)
			(layer "F.SilkS")
		)
		(fp_line
			(start -0.7874 0.4064)
			(end -0.7874 -0.4064)
			(stroke
				(width 0.1524)
				(type default)
			)
			(layer "F.SilkS")
		)
		(fp_line
			(start 0.7874 -0.4064)
			(end 0.7874 0.4064)
			(stroke
				(width 0.1524)
				(type default)
			)
			(layer "F.SilkS")
		)
		(fp_line
			(start 0.7874 0.4064)
			(end -0.7874 0.4064)
			(stroke
				(width 0.1524)
				(type default)
			)
			(layer "F.SilkS")
		)
		(fp_line
			(start -0.67945 -0.305054)
			(end -0.12065 -0.305054)
			(stroke
				(width 0.1)
				(type default)
			)
			(layer "F.Fab")
		)
		(fp_line
			(start -0.67945 0.3048)
			(end -0.67945 -0.305054)
			(stroke
				(width 0.1)
				(type default)
			)
			(layer "F.Fab")
		)
		(fp_line
			(start -0.12065 -0.305054)
			(end -0.12065 -0.2794)
			(stroke
				(width 0.1)
				(type default)
			)
			(layer "F.Fab")
		)
		(fp_line
			(start -0.12065 -0.2794)
			(end 0.12065 -0.2794)
			(stroke
				(width 0.1)
				(type default)
			)
			(layer "F.Fab")
		)
		(fp_line
			(start -0.12065 0.2794)
			(end -0.12065 0.3048)
			(stroke
				(width 0.1)
				(type default)
			)
			(layer "F.Fab")
		)
		(fp_line
			(start -0.12065 0.3048)
			(end -0.67945 0.3048)
			(stroke
				(width 0.1)
				(type default)
			)
			(layer "F.Fab")
		)
		(fp_line
			(start 0.120396 0.2794)
			(end -0.12065 0.2794)
			(stroke
				(width 0.1)
				(type default)
			)
			(layer "F.Fab")
		)
		(fp_line
			(start 0.120396 0.3048)
			(end 0.120396 0.2794)
			(stroke
				(width 0.1)
				(type default)
			)
			(layer "F.Fab")
		)
		(fp_line
			(start 0.12065 -0.3048)
			(end 0.67945 -0.3048)
			(stroke
				(width 0.1)
				(type default)
			)
			(layer "F.Fab")
		)
		(fp_line
			(start 0.12065 -0.2794)
			(end 0.12065 -0.3048)
			(stroke
				(width 0.1)
				(type default)
			)
			(layer "F.Fab")
		)
		(fp_line
			(start 0.67945 -0.3048)
			(end 0.67945 0.3048)
			(stroke
				(width 0.1)
				(type default)
			)
			(layer "F.Fab")
		)
		(fp_line
			(start 0.67945 0.3048)
			(end 0.120396 0.3048)
			(stroke
				(width 0.1)
				(type default)
			)
			(layer "F.Fab")
		)
		(pad "1" smd circle
			(at -0.40005 0)
			(size 0 0)
			(layers "F.Cu" "F.Mask" "F.Paste")
			(net "P3V3_AUX")
		)
		(pad "2" smd circle
			(at 0.40005 0)
			(size 0 0)
			(layers "F.Cu" "F.Mask" "F.Paste")
			(net "SMB_1_PLD_3V3AUX_SCL_R1")
		)
	)
	(footprint ""
		(layer "F.Cu")
		(at 115.680236 -355.985826 90)
		(property "Reference" "PJ49"
			(at -1.563878 1.821434 90)
			(unlocked yes)
			(layer "F.SilkS")
			(effects
				(font
					(size 0.7874 0.5842)
					(thickness 0.1524)
				)
				(justify left)
			)
		)
		(property "Value" ""
			(at 0 0 90)
			(layer "F.Fab")
			(effects
				(font
					(size 1.27 1.27)
				)
			)
		)
		(duplicate_pad_numbers_are_jumpers no)
		(pad "1" smd circle
			(at -0.7493 0 180)
			(size 0 0)
			(layers "F.Cu" "F.Mask" "F.Paste")
			(net "VSENSE_PVCCFA_EHV_FIVRA_CPU1_DP")
		)
		(pad "2" smd rect
			(at 0.7493 0)
			(size 0.7112 0.8128)
			(layers "F.Cu" "F.Mask" "F.Paste")
			(net "SH_PVCCFA_EHV_FIVRA_CPU1")
		)
		(zone
			(layer "F.Cu")
			(hatch none 0.5)
			(connect_pads
				(clearance 0)
			)
			(min_thickness 0.25)
			(keepout
				(tracks allowed)
				(vias not_allowed)
				(pads allowed)
				(copperpour not_allowed)
				(footprints allowed)
			)
			(placement
				(enabled no)
				(sheetname "")
			)
			(fill
				(thermal_gap 0.5)
				(thermal_bridge_width 0.5)
				(island_removal_mode 0)
			)
			(polygon
				(pts
					(xy 115.273836 -354.804726) (xy 116.091462 -354.804726) (xy 116.091462 -357.192326) (xy 115.273836 -357.192326)
				)
			)
		)
	)
	(footprint ""
		(layer "F.Cu")
		(at 48.931068 -176.180242)
		(property "Reference" "PC431"
			(at 0 0 0)
			(layer "F.SilkS")
			(hide yes)
			(effects
				(font
					(size 1.27 1.27)
				)
			)
		)
		(property "Value" ""
			(at 0 0 0)
			(layer "F.Fab")
			(effects
				(font
					(size 1.27 1.27)
				)
			)
		)
		(duplicate_pad_numbers_are_jumpers no)
		(fp_line
			(start -0.7874 -0.4064)
			(end 0.7874 -0.4064)
			(stroke
				(width 0.1524)
				(type default)
			)
			(layer "F.SilkS")
		)
		(fp_line
			(start -0.7874 0.4064)
			(end -0.7874 -0.4064)
			(stroke
				(width 0.1524)
				(type default)
			)
			(layer "F.SilkS")
		)
		(fp_line
			(start 0.7874 -0.4064)
			(end 0.7874 0.4064)
			(stroke
				(width 0.1524)
				(type default)
			)
			(layer "F.SilkS")
		)
		(fp_line
			(start 0.7874 0.4064)
			(end -0.7874 0.4064)
			(stroke
				(width 0.1524)
				(type default)
			)
			(layer "F.SilkS")
		)
		(fp_line
			(start -0.67945 -0.305054)
			(end -0.12065 -0.305054)
			(stroke
				(width 0.1)
				(type default)
			)
			(layer "F.Fab")
		)
		(fp_line
			(start -0.67945 0.3048)
			(end -0.67945 -0.305054)
			(stroke
				(width 0.1)
				(type default)
			)
			(layer "F.Fab")
		)
		(fp_line
			(start -0.12065 -0.305054)
			(end -0.12065 -0.2794)
			(stroke
				(width 0.1)
				(type default)
			)
			(layer "F.Fab")
		)
		(fp_line
			(start -0.12065 -0.2794)
			(end 0.12065 -0.2794)
			(stroke
				(width 0.1)
				(type default)
			)
			(layer "F.Fab")
		)
		(fp_line
			(start -0.12065 0.2794)
			(end -0.12065 0.3048)
			(stroke
				(width 0.1)
				(type default)
			)
			(layer "F.Fab")
		)
		(fp_line
			(start -0.12065 0.3048)
			(end -0.67945 0.3048)
			(stroke
				(width 0.1)
				(type default)
			)
			(layer "F.Fab")
		)
		(fp_line
			(start 0.120396 0.2794)
			(end -0.12065 0.2794)
			(stroke
				(width 0.1)
				(type default)
			)
			(layer "F.Fab")
		)
		(fp_line
			(start 0.120396 0.3048)
			(end 0.120396 0.2794)
			(stroke
				(width 0.1)
				(type default)
			)
			(layer "F.Fab")
		)
		(fp_line
			(start 0.12065 -0.3048)
			(end 0.67945 -0.3048)
			(stroke
				(width 0.1)
				(type default)
			)
			(layer "F.Fab")
		)
		(fp_line
			(start 0.12065 -0.2794)
			(end 0.12065 -0.3048)
			(stroke
				(width 0.1)
				(type default)
			)
			(layer "F.Fab")
		)
		(fp_line
			(start 0.67945 -0.3048)
			(end 0.67945 0.3048)
			(stroke
				(width 0.1)
				(type default)
			)
			(layer "F.Fab")
		)
		(fp_line
			(start 0.67945 0.3048)
			(end 0.120396 0.3048)
			(stroke
				(width 0.1)
				(type default)
			)
			(layer "F.Fab")
		)
		(pad "1" smd circle
			(at -0.40005 0)
			(size 0 0)
			(layers "F.Cu" "F.Mask" "F.Paste")
			(net "SW_PVCCFA_EHV_CPU1_BOOT1_R")
		)
		(pad "2" smd circle
			(at 0.40005 0)
			(size 0 0)
			(layers "F.Cu" "F.Mask" "F.Paste")
			(net "SW_PVCCFA_EHV_CPU1_BOOTR1")
		)
	)
)
